# BASEBOARD_FAB2 (Tioga Pass) — schematic netlist excerpt (pin names and nets, part order shuffled) for the footprints in the layout excerpt that follows; sources: Cadence DE-HDL packaged netlist, KiCad conversion of Wiwynn_Tioga_Pass_MB.brd

R8B25  RES  4.75K 1% CHIP  pkg 0402  page 151 : A = P3V3_STBY ; B = FM_BMC_HEARTBEAT_N
C3D16  CAP_A  22.0UF 4V 20% X6S  pkg 0603V  page 76 : A = PVCCIO_CPU1 ; B = GND
C7A21  CAP  1.0UF 16V 10% X6S  pkg 0402  page 219 : A = VR_FET_SW_P12V_STBY_PVDDQ_DEF ; B = GND

(kicad_pcb
	(version 20260206)
	(generator "pcbnew")
	(generator_version "10.0")
	(general
		(thickness 1.6)
		(legacy_teardrops no)
	)
	(paper "A4")
	(title_block
		(title "Wiwynn_Tioga_Pass_MB.brd")
		(comment 1 "Tioga Pass / footprints 1743-1745 of 4770")
	)
	(layers
		(0 "F.Cu" signal "TOP")
		(4 "In1.Cu" signal "L2GND")
		(6 "In2.Cu" signal "L3")
		(8 "In3.Cu" signal "L4GND")
		(10 "In4.Cu" signal "L5")
		(12 "In5.Cu" signal "L6GND")
		(14 "In6.Cu" signal "L7VCC")
		(16 "In7.Cu" signal "L8VCC")
		(18 "In8.Cu" signal "L9GND")
		(20 "In9.Cu" signal "L10")
		(22 "In10.Cu" signal "L11GND")
		(24 "In11.Cu" signal "L12")
		(26 "In12.Cu" signal "L13GND")
		(2 "B.Cu" signal "BOTTOM")
		(9 "F.Adhes" user "F.Adhesive")
		(11 "B.Adhes" user "B.Adhesive")
		(13 "F.Paste" user "Package Geometry/Pastemask Top")
		(15 "B.Paste" user "Package Geometry/Pastemask Bottom")
		(5 "F.SilkS" user "Ref Des/Silkscreen Top")
		(7 "B.SilkS" user "Ref Des/Silkscreen Bottom")
		(1 "F.Mask" user "Board Geometry/Soldermask Top")
		(3 "B.Mask" user "Board Geometry/Soldermask Bottom")
		(17 "Dwgs.User" user "User.Drawings")
		(19 "Cmts.User" user "User.Comments")
		(21 "Eco1.User" user "User.Eco1")
		(23 "Eco2.User" user "User.Eco2")
		(25 "Edge.Cuts" user "Board Geometry/Outline")
		(27 "Margin" user)
		(31 "F.CrtYd" user "Package Geometry/Place Bound Top")
		(29 "B.CrtYd" user "Package Geometry/Place Bound Bottom")
		(35 "F.Fab" user "Ref Des/Assembly Top")
		(33 "B.Fab" user "Ref Des/Assembly Bottom")
	)
	(footprint ""
		(layer "F.Cu")
		(at 114.671602 -77.382116)
		(property "Reference" "C3D16"
			(at 0 0 0)
			(layer "F.SilkS")
			(hide yes)
			(effects
				(font
					(size 1.27 1.27)
				)
			)
		)
		(property "Value" ""
			(at 0 0 0)
			(layer "F.Fab")
			(effects
				(font
					(size 1.27 1.27)
				)
			)
		)
		(duplicate_pad_numbers_are_jumpers no)
		(fp_poly
			(pts
				(xy -0.4953 -0.2032) (xy 0.4953 -0.2032) (xy 0.4953 1.6002) (xy -0.4953 1.6002)
			)
			(stroke
				(width 0)
				(type default)
			)
			(fill no)
			(layer "F.CrtYd")
		)
		(fp_line
			(start -0.4953 -0.2032)
			(end 0.4953 -0.2032)
			(stroke
				(width 0.1)
				(type default)
			)
			(layer "F.Fab")
		)
		(fp_line
			(start -0.4953 1.6002)
			(end -0.4953 -0.2032)
			(stroke
				(width 0.1)
				(type default)
			)
			(layer "F.Fab")
		)
		(fp_line
			(start 0.4953 -0.2032)
			(end 0.4953 1.6002)
			(stroke
				(width 0.1)
				(type default)
			)
			(layer "F.Fab")
		)
		(fp_line
			(start 0.4953 1.6002)
			(end -0.4953 1.6002)
			(stroke
				(width 0.1)
				(type default)
			)
			(layer "F.Fab")
		)
		(pad "1" smd rect
			(at 0 0)
			(size 0.762 0.889)
			(layers "F.Cu" "F.Mask" "F.Paste")
			(net "PVCCIO_CPU1")
		)
		(pad "2" smd rect
			(at 0 1.397)
			(size 0.762 0.889)
			(layers "F.Cu" "F.Mask" "F.Paste")
			(net "GND")
		)
		(zone
			(layer "F.Cu")
			(hatch none 0.5)
			(connect_pads
				(clearance 0)
			)
			(min_thickness 0.25)
			(keepout
				(tracks not_allowed)
				(vias allowed)
				(pads allowed)
				(copperpour not_allowed)
				(footprints allowed)
			)
			(placement
				(enabled no)
				(sheetname "")
			)
			(fill
				(thermal_gap 0.5)
				(thermal_bridge_width 0.5)
				(island_removal_mode 0)
			)
			(polygon
				(pts
					(xy 114.290602 -76.937616) (xy 115.052602 -76.937616) (xy 115.052602 -76.429616) (xy 114.290602 -76.429616)
				)
			)
		)
	)
	(footprint ""
		(layer "F.Cu")
		(at 457.83119 -35.569906)
		(property "Reference" "R8B25"
			(at 0 0 0)
			(layer "F.SilkS")
			(hide yes)
			(effects
				(font
					(size 1.27 1.27)
				)
			)
		)
		(property "Value" ""
			(at 0 0 0)
			(layer "F.Fab")
			(effects
				(font
					(size 1.27 1.27)
				)
			)
		)
		(duplicate_pad_numbers_are_jumpers no)
		(fp_poly
			(pts
				(xy -0.2794 -0.1016) (xy 0.2794 -0.1016) (xy 0.2794 0.9906) (xy -0.2794 0.9906)
			)
			(stroke
				(width 0)
				(type default)
			)
			(fill no)
			(layer "F.CrtYd")
		)
		(fp_line
			(start -0.2794 -0.1016)
			(end -0.2794 0.9906)
			(stroke
				(width 0.1)
				(type default)
			)
			(layer "F.Fab")
		)
		(fp_line
			(start -0.2794 0.9906)
			(end 0.2794 0.9906)
			(stroke
				(width 0.1)
				(type default)
			)
			(layer "F.Fab")
		)
		(fp_line
			(start 0.2794 -0.1016)
			(end -0.2794 -0.1016)
			(stroke
				(width 0.1)
				(type default)
			)
			(layer "F.Fab")
		)
		(fp_line
			(start 0.2794 0.9906)
			(end 0.2794 -0.1016)
			(stroke
				(width 0.1)
				(type default)
			)
			(layer "F.Fab")
		)
		(pad "1" smd rect
			(at 0 0)
			(size 0.508 0.508)
			(layers "F.Cu" "F.Mask" "F.Paste")
			(net "P3V3_STBY")
		)
		(pad "2" smd rect
			(at 0 0.889)
			(size 0.508 0.508)
			(layers "F.Cu" "F.Mask" "F.Paste")
			(net "FM_BMC_HEARTBEAT_N")
		)
		(zone
			(layer "F.Cu")
			(hatch none 0.5)
			(connect_pads
				(clearance 0)
			)
			(min_thickness 0.25)
			(keepout
				(tracks allowed)
				(vias not_allowed)
				(pads allowed)
				(copperpour not_allowed)
				(footprints allowed)
			)
			(placement
				(enabled no)
				(sheetname "")
			)
			(fill
				(thermal_gap 0.5)
				(thermal_bridge_width 0.5)
				(island_removal_mode 0)
			)
			(polygon
				(pts
					(xy 457.57719 -35.315906) (xy 458.08519 -35.315906) (xy 458.08519 -34.934906) (xy 457.57719 -34.934906)
				)
			)
		)
		(zone
			(layer "F.Cu")
			(hatch none 0.5)
			(connect_pads
				(clearance 0)
			)
			(min_thickness 0.25)
			(keepout
				(tracks not_allowed)
				(vias allowed)
				(pads allowed)
				(copperpour not_allowed)
				(footprints allowed)
			)
			(placement
				(enabled no)
				(sheetname "")
			)
			(fill
				(thermal_gap 0.5)
				(thermal_bridge_width 0.5)
				(island_removal_mode 0)
			)
			(polygon
				(pts
					(xy 457.57719 -34.934906) (xy 458.08519 -34.934906) (xy 458.08519 -35.315906) (xy 457.57719 -35.315906)
				)
			)
		)
	)
	(footprint ""
		(layer "F.Cu")
		(at 347.975936 -140.575538 -90)
		(property "Reference" "C7A21"
			(at 0 0 270)
			(layer "F.SilkS")
			(hide yes)
			(effects
				(font
					(size 1.27 1.27)
				)
			)
		)
		(property "Value" ""
			(at 0 0 270)
			(layer "F.Fab")
			(effects
				(font
					(size 1.27 1.27)
				)
			)
		)
		(duplicate_pad_numbers_are_jumpers no)
		(fp_poly
			(pts
				(xy 0.3048 -0.1016) (xy 0.3048 0.9906) (xy -0.3048 0.9906) (xy -0.3048 -0.1016)
			)
			(stroke
				(width 0)
				(type default)
			)
			(fill no)
			(layer "F.CrtYd")
		)
		(fp_line
			(start -0.3048 0.9906)
			(end 0.3048 0.9906)
			(stroke
				(width 0.1)
				(type default)
			)
			(layer "F.Fab")
		)
		(fp_line
			(start 0.3048 0.9906)
			(end 0.3048 -0.1016)
			(stroke
				(width 0.1)
				(type default)
			)
			(layer "F.Fab")
		)
		(fp_line
			(start -0.3048 -0.1016)
			(end -0.3048 0.9906)
			(stroke
				(width 0.1)
				(type default)
			)
			(layer "F.Fab")
		)
		(fp_line
			(start 0.3048 -0.1016)
			(end -0.3048 -0.1016)
			(stroke
				(width 0.1)
				(type default)
			)
			(layer "F.Fab")
		)
		(pad "1" smd rect
			(at 0 0 270)
			(size 0.508 0.508)
			(layers "F.Cu" "F.Mask" "F.Paste")
			(net "VR_FET_SW_P12V_STBY_PVDDQ_DEF")
		)
		(pad "2" smd rect
			(at 0 0.889 270)
			(size 0.508 0.508)
			(layers "F.Cu" "F.Mask" "F.Paste")
			(net "GND")
		)
		(zone
			(layer "F.Cu")
			(hatch none 0.5)
			(connect_pads
				(clearance 0)
			)
			(min_thickness 0.25)
			(keepout
				(tracks not_allowed)
				(vias allowed)
				(pads allowed)
				(copperpour not_allowed)
				(footprints allowed)
			)
			(placement
				(enabled no)
				(sheetname "")
			)
			(fill
				(thermal_gap 0.5)
				(thermal_bridge_width 0.5)
				(island_removal_mode 0)
			)
			(polygon
				(pts
					(xy 347.340936 -140.829538) (xy 347.340936 -140.321538) (xy 347.721936 -140.321538) (xy 347.721936 -140.829538)
				)
			)
		)
		(zone
			(layer "F.Cu")
			(hatch none 0.5)
			(connect_pads
				(clearance 0)
			)
			(min_thickness 0.25)
			(keepout
				(tracks allowed)
				(vias not_allowed)
				(pads allowed)
				(copperpour not_allowed)
				(footprints allowed)
			)
			(placement
				(enabled no)
				(sheetname "")
			)
			(fill
				(thermal_gap 0.5)
				(thermal_bridge_width 0.5)
				(island_removal_mode 0)
			)
			(polygon
				(pts
					(xy 347.721936 -140.829538) (xy 347.721936 -140.321538) (xy 347.340936 -140.321538) (xy 347.340936 -140.829538)
				)
			)
		)
	)
)
